FILE_TYPE=LIBRARY_PARTS;
primitive 'K4B1G16', 'K4B1G16_BGA';
  pin
    'A0':
      PIN_NUMBER='(N3)';
      INPUT_LOAD='(-0.01,0.01)';
    'A1':
      PIN_NUMBER='(P7)';
      INPUT_LOAD='(-0.01,0.01)';
    'A10_AP':
      PIN_NUMBER='(L7)';
      INPUT_LOAD='(-0.01,0.01)';
    'A11':
      PIN_NUMBER='(R7)';
      INPUT_LOAD='(-0.01,0.01)';
    'A12':
      PIN_NUMBER='(N7)';
      INPUT_LOAD='(-0.01,0.01)';
    'A13':
      PIN_NUMBER='(T3)';
      INPUT_LOAD='(-0.01,0.01)';
    'A14':
      PIN_NUMBER='(T7)';
      INPUT_LOAD='(-0.01,0.01)';
    'A15_BA3':
      PIN_NUMBER='(M7)';
      INPUT_LOAD='(-0.01,0.01)';
    'A2':
      PIN_NUMBER='(P3)';
      INPUT_LOAD='(-0.01,0.01)';
    'A3':
      PIN_NUMBER='(N2)';
      INPUT_LOAD='(-0.01,0.01)';
    'A4':
      PIN_NUMBER='(P8)';
      INPUT_LOAD='(-0.01,0.01)';
    'A5':
      PIN_NUMBER='(P2)';
      INPUT_LOAD='(-0.01,0.01)';
    'A6':
      PIN_NUMBER='(R8)';
      INPUT_LOAD='(-0.01,0.01)';
    'A7':
      PIN_NUMBER='(R2)';
      INPUT_LOAD='(-0.01,0.01)';
    'A8':
      PIN_NUMBER='(T8)';
      INPUT_LOAD='(-0.01,0.01)';
    'A9':
      PIN_NUMBER='(R3)';
      INPUT_LOAD='(-0.01,0.01)';
    'BA0':
      PIN_NUMBER='(M2)';
      INPUT_LOAD='(-0.01,0.01)';
    'BA1':
      PIN_NUMBER='(N8)';
      INPUT_LOAD='(-0.01,0.01)';
    'BA2':
      PIN_NUMBER='(M3)';
      INPUT_LOAD='(-0.01,0.01)';
    'CAS_N':
      PIN_NUMBER='(K3)';
      INPUT_LOAD='(-0.01,0.01)';
    'CE1_NC'<1>:
      PIN_NUMBER='(J9)';
      BIDIRECTIONAL='TRUE';
      INPUT_LOAD='(-0.01,0.01)';
      OUTPUT_LOAD='(1.0,-1.0)';
    'CK':
      PIN_NUMBER='(J7)';
      INPUT_LOAD='(-0.01,0.01)';
    'CKE_CKE0':
      PIN_NUMBER='(K9)';
      INPUT_LOAD='(-0.01,0.01)';
    'CK_N':
      PIN_NUMBER='(K7)';
      INPUT_LOAD='(-0.01,0.01)';
    'CS1_N_NC'<2>:
      PIN_NUMBER='(L1)';
      BIDIRECTIONAL='TRUE';
      INPUT_LOAD='(-0.01,0.01)';
      OUTPUT_LOAD='(1.0,-1.0)';
    'CS_N_CS0_N':
      PIN_NUMBER='(L2)';
      INPUT_LOAD='(-0.01,0.01)';
    'DML':
      PIN_NUMBER='(E7)';
      INPUT_LOAD='(-0.01,0.01)';
    'DMU':
      PIN_NUMBER='(D3)';
      INPUT_LOAD='(-0.01,0.01)';
    'DQL0':
      PIN_NUMBER='(E3)';
      BIDIRECTIONAL='TRUE';
      INPUT_LOAD='(-0.01,0.01)';
      OUTPUT_LOAD='(1.0,-1.0)';
    'DQL1':
      PIN_NUMBER='(F7)';
      BIDIRECTIONAL='TRUE';
      INPUT_LOAD='(-0.01,0.01)';
      OUTPUT_LOAD='(1.0,-1.0)';
    'DQL2':
      PIN_NUMBER='(F2)';
      BIDIRECTIONAL='TRUE';
      INPUT_LOAD='(-0.01,0.01)';
      OUTPUT_LOAD='(1.0,-1.0)';
    'DQL3':
      PIN_NUMBER='(F8)';
      BIDIRECTIONAL='TRUE';
      INPUT_LOAD='(-0.01,0.01)';
      OUTPUT_LOAD='(1.0,-1.0)';
    'DQL4':
      PIN_NUMBER='(H3)';
      BIDIRECTIONAL='TRUE';
      INPUT_LOAD='(-0.01,0.01)';
      OUTPUT_LOAD='(1.0,-1.0)';
    'DQL5':
      PIN_NUMBER='(H8)';
      BIDIRECTIONAL='TRUE';
      INPUT_LOAD='(-0.01,0.01)';
      OUTPUT_LOAD='(1.0,-1.0)';
    'DQL6':
      PIN_NUMBER='(G2)';
      BIDIRECTIONAL='TRUE';
      INPUT_LOAD='(-0.01,0.01)';
      OUTPUT_LOAD='(1.0,-1.0)';
    'DQL7':
      PIN_NUMBER='(H7)';
      BIDIRECTIONAL='TRUE';
      INPUT_LOAD='(-0.01,0.01)';
      OUTPUT_LOAD='(1.0,-1.0)';
    'DQSL':
      PIN_NUMBER='(F3)';
      BIDIRECTIONAL='TRUE';
      INPUT_LOAD='(-0.01,0.01)';
      OUTPUT_LOAD='(1.0,-1.0)';
    'DQSL_N':
      PIN_NUMBER='(G3)';
      BIDIRECTIONAL='TRUE';
      INPUT_LOAD='(-0.01,0.01)';
      OUTPUT_LOAD='(1.0,-1.0)';
    'DQSU':
      PIN_NUMBER='(C7)';
      BIDIRECTIONAL='TRUE';
      INPUT_LOAD='(-0.01,0.01)';
      OUTPUT_LOAD='(1.0,-1.0)';
    'DQSU_N':
      PIN_NUMBER='(B7)';
      BIDIRECTIONAL='TRUE';
      INPUT_LOAD='(-0.01,0.01)';
      OUTPUT_LOAD='(1.0,-1.0)';
    'DQU0':
      PIN_NUMBER='(D7)';
      BIDIRECTIONAL='TRUE';
      INPUT_LOAD='(-0.01,0.01)';
      OUTPUT_LOAD='(1.0,-1.0)';
    'DQU1':
      PIN_NUMBER='(C3)';
      BIDIRECTIONAL='TRUE';
      INPUT_LOAD='(-0.01,0.01)';
      OUTPUT_LOAD='(1.0,-1.0)';
    'DQU2':
      PIN_NUMBER='(C8)';
      BIDIRECTIONAL='TRUE';
      INPUT_LOAD='(-0.01,0.01)';
      OUTPUT_LOAD='(1.0,-1.0)';
    'DQU3':
      PIN_NUMBER='(C2)';
      BIDIRECTIONAL='TRUE';
      INPUT_LOAD='(-0.01,0.01)';
      OUTPUT_LOAD='(1.0,-1.0)';
    'DQU4':
      PIN_NUMBER='(A7)';
      BIDIRECTIONAL='TRUE';
      INPUT_LOAD='(-0.01,0.01)';
      OUTPUT_LOAD='(1.0,-1.0)';
    'DQU5':
      PIN_NUMBER='(A2)';
      BIDIRECTIONAL='TRUE';
      INPUT_LOAD='(-0.01,0.01)';
      OUTPUT_LOAD='(1.0,-1.0)';
    'DQU6':
      PIN_NUMBER='(B8)';
      BIDIRECTIONAL='TRUE';
      INPUT_LOAD='(-0.01,0.01)';
      OUTPUT_LOAD='(1.0,-1.0)';
    'DQU7':
      PIN_NUMBER='(A3)';
      BIDIRECTIONAL='TRUE';
      INPUT_LOAD='(-0.01,0.01)';
      OUTPUT_LOAD='(1.0,-1.0)';
    'ODT_1NC'<0>:
      PIN_NUMBER='(J1)';
      BIDIRECTIONAL='TRUE';
      INPUT_LOAD='(-0.01,0.01)';
      OUTPUT_LOAD='(1.0,-1.0)';
    'ODT_ODT0':
      PIN_NUMBER='(K1)';
      INPUT_LOAD='(-0.01,0.01)';
    'RAS_N':
      PIN_NUMBER='(J3)';
      INPUT_LOAD='(-0.01,0.01)';
    'RESET_N':
      PIN_NUMBER='(T2)';
      INPUT_LOAD='(-0.01,0.01)';
    'VDD'<8>:
      PIN_NUMBER='(R9)';
      PINUSE='POWER';
      NO_LOAD_CHECK='Both';
      NO_IO_CHECK='Both';
      NO_ASSERT_CHECK='TRUE';
      NO_DIR_CHECK='TRUE';
      ALLOW_CONNECT='TRUE';
    'VDD'<7>:
      PIN_NUMBER='(R1)';
      PINUSE='POWER';
      NO_LOAD_CHECK='Both';
      NO_IO_CHECK='Both';
      NO_ASSERT_CHECK='TRUE';
      NO_DIR_CHECK='TRUE';
      ALLOW_CONNECT='TRUE';
    'VDD'<6>:
      PIN_NUMBER='(N9)';
      PINUSE='POWER';
      NO_LOAD_CHECK='Both';
      NO_IO_CHECK='Both';
      NO_ASSERT_CHECK='TRUE';
      NO_DIR_CHECK='TRUE';
      ALLOW_CONNECT='TRUE';
    'VDD'<5>:
      PIN_NUMBER='(N1)';
      PINUSE='POWER';
      NO_LOAD_CHECK='Both';
      NO_IO_CHECK='Both';
      NO_ASSERT_CHECK='TRUE';
      NO_DIR_CHECK='TRUE';
      ALLOW_CONNECT='TRUE';
    'VDD'<4>:
      PIN_NUMBER='(K8)';
      PINUSE='POWER';
      NO_LOAD_CHECK='Both';
      NO_IO_CHECK='Both';
      NO_ASSERT_CHECK='TRUE';
      NO_DIR_CHECK='TRUE';
      ALLOW_CONNECT='TRUE';
    'VDD'<3>:
      PIN_NUMBER='(K2)';
      PINUSE='POWER';
      NO_LOAD_CHECK='Both';
      NO_IO_CHECK='Both';
      NO_ASSERT_CHECK='TRUE';
      NO_DIR_CHECK='TRUE';
      ALLOW_CONNECT='TRUE';
    'VDD'<2>:
      PIN_NUMBER='(G7)';
      PINUSE='POWER';
      NO_LOAD_CHECK='Both';
      NO_IO_CHECK='Both';
      NO_ASSERT_CHECK='TRUE';
      NO_DIR_CHECK='TRUE';
      ALLOW_CONNECT='TRUE';
    'VDD'<1>:
      PIN_NUMBER='(D9)';
      PINUSE='POWER';
      NO_LOAD_CHECK='Both';
      NO_IO_CHECK='Both';
      NO_ASSERT_CHECK='TRUE';
      NO_DIR_CHECK='TRUE';
      ALLOW_CONNECT='TRUE';
    'VDD'<0>:
      PIN_NUMBER='(B2)';
      PINUSE='POWER';
      NO_LOAD_CHECK='Both';
      NO_IO_CHECK='Both';
      NO_ASSERT_CHECK='TRUE';
      NO_DIR_CHECK='TRUE';
      ALLOW_CONNECT='TRUE';
    'VDDQ'<8>:
      PIN_NUMBER='(H9)';
      PINUSE='POWER';
      NO_LOAD_CHECK='Both';
      NO_IO_CHECK='Both';
      NO_ASSERT_CHECK='TRUE';
      NO_DIR_CHECK='TRUE';
      ALLOW_CONNECT='TRUE';
    'VDDQ'<7>:
      PIN_NUMBER='(H2)';
      PINUSE='POWER';
      NO_LOAD_CHECK='Both';
      NO_IO_CHECK='Both';
      NO_ASSERT_CHECK='TRUE';
      NO_DIR_CHECK='TRUE';
      ALLOW_CONNECT='TRUE';
    'VDDQ'<6>:
      PIN_NUMBER='(F1)';
      PINUSE='POWER';
      NO_LOAD_CHECK='Both';
      NO_IO_CHECK='Both';
      NO_ASSERT_CHECK='TRUE';
      NO_DIR_CHECK='TRUE';
      ALLOW_CONNECT='TRUE';
    'VDDQ'<5>:
      PIN_NUMBER='(E9)';
      PINUSE='POWER';
      NO_LOAD_CHECK='Both';
      NO_IO_CHECK='Both';
      NO_ASSERT_CHECK='TRUE';
      NO_DIR_CHECK='TRUE';
      ALLOW_CONNECT='TRUE';
    'VDDQ'<4>:
      PIN_NUMBER='(D2)';
      PINUSE='POWER';
      NO_LOAD_CHECK='Both';
      NO_IO_CHECK='Both';
      NO_ASSERT_CHECK='TRUE';
      NO_DIR_CHECK='TRUE';
      ALLOW_CONNECT='TRUE';
    'VDDQ'<3>:
      PIN_NUMBER='(C9)';
      PINUSE='POWER';
      NO_LOAD_CHECK='Both';
      NO_IO_CHECK='Both';
      NO_ASSERT_CHECK='TRUE';
      NO_DIR_CHECK='TRUE';
      ALLOW_CONNECT='TRUE';
    'VDDQ'<2>:
      PIN_NUMBER='(C1)';
      PINUSE='POWER';
      NO_LOAD_CHECK='Both';
      NO_IO_CHECK='Both';
      NO_ASSERT_CHECK='TRUE';
      NO_DIR_CHECK='TRUE';
      ALLOW_CONNECT='TRUE';
    'VDDQ'<1>:
      PIN_NUMBER='(A8)';
      PINUSE='POWER';
      NO_LOAD_CHECK='Both';
      NO_IO_CHECK='Both';
      NO_ASSERT_CHECK='TRUE';
      NO_DIR_CHECK='TRUE';
      ALLOW_CONNECT='TRUE';
    'VDDQ'<0>:
      PIN_NUMBER='(A1)';
      PINUSE='POWER';
      NO_LOAD_CHECK='Both';
      NO_IO_CHECK='Both';
      NO_ASSERT_CHECK='TRUE';
      NO_DIR_CHECK='TRUE';
      ALLOW_CONNECT='TRUE';
    'VREFCA':
      PIN_NUMBER='(M8)';
      BIDIRECTIONAL='TRUE';
      INPUT_LOAD='(-0.01,0.01)';
      OUTPUT_LOAD='(1.0,-1.0)';
    'VREFDQ':
      PIN_NUMBER='(H1)';
      BIDIRECTIONAL='TRUE';
      INPUT_LOAD='(-0.01,0.01)';
      OUTPUT_LOAD='(1.0,-1.0)';
    'VSS'<11>:
      PIN_NUMBER='(T9)';
      PINUSE='GROUND';
      NO_LOAD_CHECK='Both';
      NO_IO_CHECK='Both';
      NO_ASSERT_CHECK='TRUE';
      NO_DIR_CHECK='TRUE';
      ALLOW_CONNECT='TRUE';
    'VSS'<10>:
      PIN_NUMBER='(T1)';
      PINUSE='GROUND';
      NO_LOAD_CHECK='Both';
      NO_IO_CHECK='Both';
      NO_ASSERT_CHECK='TRUE';
      NO_DIR_CHECK='TRUE';
      ALLOW_CONNECT='TRUE';
    'VSS'<9>:
      PIN_NUMBER='(P9)';
      PINUSE='GROUND';
      NO_LOAD_CHECK='Both';
      NO_IO_CHECK='Both';
      NO_ASSERT_CHECK='TRUE';
      NO_DIR_CHECK='TRUE';
      ALLOW_CONNECT='TRUE';
    'VSS'<8>:
      PIN_NUMBER='(P1)';
      PINUSE='GROUND';
      NO_LOAD_CHECK='Both';
      NO_IO_CHECK='Both';
      NO_ASSERT_CHECK='TRUE';
      NO_DIR_CHECK='TRUE';
      ALLOW_CONNECT='TRUE';
    'VSS'<7>:
      PIN_NUMBER='(M9)';
      PINUSE='GROUND';
      NO_LOAD_CHECK='Both';
      NO_IO_CHECK='Both';
      NO_ASSERT_CHECK='TRUE';
      NO_DIR_CHECK='TRUE';
      ALLOW_CONNECT='TRUE';
    'VSS'<6>:
      PIN_NUMBER='(M1)';
      PINUSE='GROUND';
      NO_LOAD_CHECK='Both';
      NO_IO_CHECK='Both';
      NO_ASSERT_CHECK='TRUE';
      NO_DIR_CHECK='TRUE';
      ALLOW_CONNECT='TRUE';
    'VSS'<5>:
      PIN_NUMBER='(J8)';
      PINUSE='GROUND';
      NO_LOAD_CHECK='Both';
      NO_IO_CHECK='Both';
      NO_ASSERT_CHECK='TRUE';
      NO_DIR_CHECK='TRUE';
      ALLOW_CONNECT='TRUE';
    'VSS'<4>:
      PIN_NUMBER='(J2)';
      PINUSE='GROUND';
      NO_LOAD_CHECK='Both';
      NO_IO_CHECK='Both';
      NO_ASSERT_CHECK='TRUE';
      NO_DIR_CHECK='TRUE';
      ALLOW_CONNECT='TRUE';
    'VSS'<3>:
      PIN_NUMBER='(G8)';
      PINUSE='GROUND';
      NO_LOAD_CHECK='Both';
      NO_IO_CHECK='Both';
      NO_ASSERT_CHECK='TRUE';
      NO_DIR_CHECK='TRUE';
      ALLOW_CONNECT='TRUE';
    'VSS'<2>:
      PIN_NUMBER='(E1)';
      PINUSE='GROUND';
      NO_LOAD_CHECK='Both';
      NO_IO_CHECK='Both';
      NO_ASSERT_CHECK='TRUE';
      NO_DIR_CHECK='TRUE';
      ALLOW_CONNECT='TRUE';
    'VSS'<1>:
      PIN_NUMBER='(B3)';
      PINUSE='GROUND';
      NO_LOAD_CHECK='Both';
      NO_IO_CHECK='Both';
      NO_ASSERT_CHECK='TRUE';
      NO_DIR_CHECK='TRUE';
      ALLOW_CONNECT='TRUE';
    'VSS'<0>:
      PIN_NUMBER='(A9)';
      PINUSE='GROUND';
      NO_LOAD_CHECK='Both';
      NO_IO_CHECK='Both';
      NO_ASSERT_CHECK='TRUE';
      NO_DIR_CHECK='TRUE';
      ALLOW_CONNECT='TRUE';
    'VSSQ'<8>:
      PIN_NUMBER='(G9)';
      PINUSE='GROUND';
      NO_LOAD_CHECK='Both';
      NO_IO_CHECK='Both';
      NO_ASSERT_CHECK='TRUE';
      NO_DIR_CHECK='TRUE';
      ALLOW_CONNECT='TRUE';
    'VSSQ'<7>:
      PIN_NUMBER='(G1)';
      PINUSE='GROUND';
      NO_LOAD_CHECK='Both';
      NO_IO_CHECK='Both';
      NO_ASSERT_CHECK='TRUE';
      NO_DIR_CHECK='TRUE';
      ALLOW_CONNECT='TRUE';
    'VSSQ'<6>:
      PIN_NUMBER='(F9)';
      PINUSE='GROUND';
      NO_LOAD_CHECK='Both';
      NO_IO_CHECK='Both';
      NO_ASSERT_CHECK='TRUE';
      NO_DIR_CHECK='TRUE';
      ALLOW_CONNECT='TRUE';
    'VSSQ'<5>:
      PIN_NUMBER='(E8)';
      PINUSE='GROUND';
      NO_LOAD_CHECK='Both';
      NO_IO_CHECK='Both';
      NO_ASSERT_CHECK='TRUE';
      NO_DIR_CHECK='TRUE';
      ALLOW_CONNECT='TRUE';
    'VSSQ'<4>:
      PIN_NUMBER='(E2)';
      PINUSE='GROUND';
      NO_LOAD_CHECK='Both';
      NO_IO_CHECK='Both';
      NO_ASSERT_CHECK='TRUE';
      NO_DIR_CHECK='TRUE';
      ALLOW_CONNECT='TRUE';
    'VSSQ'<3>:
      PIN_NUMBER='(D8)';
      PINUSE='GROUND';
      NO_LOAD_CHECK='Both';
      NO_IO_CHECK='Both';
      NO_ASSERT_CHECK='TRUE';
      NO_DIR_CHECK='TRUE';
      ALLOW_CONNECT='TRUE';
    'VSSQ'<2>:
      PIN_NUMBER='(D1)';
      PINUSE='GROUND';
      NO_LOAD_CHECK='Both';
      NO_IO_CHECK='Both';
      NO_ASSERT_CHECK='TRUE';
      NO_DIR_CHECK='TRUE';
      ALLOW_CONNECT='TRUE';
    'VSSQ'<1>:
      PIN_NUMBER='(B9)';
      PINUSE='GROUND';
      NO_LOAD_CHECK='Both';
      NO_IO_CHECK='Both';
      NO_ASSERT_CHECK='TRUE';
      NO_DIR_CHECK='TRUE';
      ALLOW_CONNECT='TRUE';
    'VSSQ'<0>:
      PIN_NUMBER='(B1)';
      PINUSE='GROUND';
      NO_LOAD_CHECK='Both';
      NO_IO_CHECK='Both';
      NO_ASSERT_CHECK='TRUE';
      NO_DIR_CHECK='TRUE';
      ALLOW_CONNECT='TRUE';
    'WE_N':
      PIN_NUMBER='(L3)';
      INPUT_LOAD='(-0.01,0.01)';
    'ZQ1_NC'<3>:
      PIN_NUMBER='(L9)';
      BIDIRECTIONAL='TRUE';
      INPUT_LOAD='(-0.01,0.01)';
      OUTPUT_LOAD='(1.0,-1.0)';
    'ZQ_ZQ0':
      PIN_NUMBER='(L8)';
      BIDIRECTIONAL='TRUE';
      INPUT_LOAD='(-0.01,0.01)';
      OUTPUT_LOAD='(1.0,-1.0)';
  end_pin;
  body
    PART_NAME='K4B1G16';
    PHYS_DES_PREFIX='U';
  end_body;
end_primitive;
primitive 'K4B1G16_BGA1','K4B1G16_TMP_BGA2';
  pin
    'A0':
      PIN_NUMBER='(N3)';
      INPUT_LOAD='(-0.01,0.01)';
    'A1':
      PIN_NUMBER='(P7)';
      INPUT_LOAD='(-0.01,0.01)';
    'A10_AP':
      PIN_NUMBER='(L7)';
      INPUT_LOAD='(-0.01,0.01)';
    'A11':
      PIN_NUMBER='(R7)';
      INPUT_LOAD='(-0.01,0.01)';
    'A12/BC_N':
      PIN_NUMBER='(N7)';
      INPUT_LOAD='(-0.01,0.01)';
    'A2':
      PIN_NUMBER='(P3)';
      INPUT_LOAD='(-0.01,0.01)';
    'A3':
      PIN_NUMBER='(N2)';
      INPUT_LOAD='(-0.01,0.01)';
    'A4':
      PIN_NUMBER='(P8)';
      INPUT_LOAD='(-0.01,0.01)';
    'A5':
      PIN_NUMBER='(P2)';
      INPUT_LOAD='(-0.01,0.01)';
    'A6':
      PIN_NUMBER='(R8)';
      INPUT_LOAD='(-0.01,0.01)';
    'A7':
      PIN_NUMBER='(R2)';
      INPUT_LOAD='(-0.01,0.01)';
    'A8':
      PIN_NUMBER='(T8)';
      INPUT_LOAD='(-0.01,0.01)';
    'A9':
      PIN_NUMBER='(R3)';
      INPUT_LOAD='(-0.01,0.01)';
    'BA0':
      PIN_NUMBER='(M2)';
      INPUT_LOAD='(-0.01,0.01)';
    'BA1':
      PIN_NUMBER='(N8)';
      INPUT_LOAD='(-0.01,0.01)';
    'BA2':
      PIN_NUMBER='(M3)';
      INPUT_LOAD='(-0.01,0.01)';
    'CAS_N':
      PIN_NUMBER='(K3)';
      INPUT_LOAD='(-0.01,0.01)';
    'CK':
      PIN_NUMBER='(J7)';
      INPUT_LOAD='(-0.01,0.01)';
    'CKE':
      PIN_NUMBER='(K9)';
      INPUT_LOAD='(-0.01,0.01)';
    'CK_N':
      PIN_NUMBER='(K7)';
      INPUT_LOAD='(-0.01,0.01)';
    'CS_N':
      PIN_NUMBER='(L2)';
      INPUT_LOAD='(-0.01,0.01)';
    'DML':
      PIN_NUMBER='(E7)';
      INPUT_LOAD='(-0.01,0.01)';
    'DMU':
      PIN_NUMBER='(D3)';
      INPUT_LOAD='(-0.01,0.01)';
    'DQL0':
      PIN_NUMBER='(E3)';
      BIDIRECTIONAL='TRUE';
      INPUT_LOAD='(-0.01,0.01)';
      OUTPUT_LOAD='(1.0,-1.0)';
    'DQL1':
      PIN_NUMBER='(F7)';
      BIDIRECTIONAL='TRUE';
      INPUT_LOAD='(-0.01,0.01)';
      OUTPUT_LOAD='(1.0,-1.0)';
    'DQL2':
      PIN_NUMBER='(F2)';
      BIDIRECTIONAL='TRUE';
      INPUT_LOAD='(-0.01,0.01)';
      OUTPUT_LOAD='(1.0,-1.0)';
    'DQL3':
      PIN_NUMBER='(F8)';
      BIDIRECTIONAL='TRUE';
      INPUT_LOAD='(-0.01,0.01)';
      OUTPUT_LOAD='(1.0,-1.0)';
    'DQL4':
      PIN_NUMBER='(H3)';
      BIDIRECTIONAL='TRUE';
      INPUT_LOAD='(-0.01,0.01)';
      OUTPUT_LOAD='(1.0,-1.0)';
    'DQL5':
      PIN_NUMBER='(H8)';
      BIDIRECTIONAL='TRUE';
      INPUT_LOAD='(-0.01,0.01)';
      OUTPUT_LOAD='(1.0,-1.0)';
    'DQL6':
      PIN_NUMBER='(G2)';
      BIDIRECTIONAL='TRUE';
      INPUT_LOAD='(-0.01,0.01)';
      OUTPUT_LOAD='(1.0,-1.0)';
    'DQL7':
      PIN_NUMBER='(H7)';
      BIDIRECTIONAL='TRUE';
      INPUT_LOAD='(-0.01,0.01)';
      OUTPUT_LOAD='(1.0,-1.0)';
    'DQSL':
      PIN_NUMBER='(F3)';
      BIDIRECTIONAL='TRUE';
      INPUT_LOAD='(-0.01,0.01)';
      OUTPUT_LOAD='(1.0,-1.0)';
    'DQSL_N':
      PIN_NUMBER='(G3)';
      BIDIRECTIONAL='TRUE';
      INPUT_LOAD='(-0.01,0.01)';
      OUTPUT_LOAD='(1.0,-1.0)';
    'DQSU':
      PIN_NUMBER='(C7)';
      BIDIRECTIONAL='TRUE';
      INPUT_LOAD='(-0.01,0.01)';
      OUTPUT_LOAD='(1.0,-1.0)';
    'DQSU_N':
      PIN_NUMBER='(B7)';
      BIDIRECTIONAL='TRUE';
      INPUT_LOAD='(-0.01,0.01)';
      OUTPUT_LOAD='(1.0,-1.0)';
    'DQU0':
      PIN_NUMBER='(D7)';
      BIDIRECTIONAL='TRUE';
      INPUT_LOAD='(-0.01,0.01)';
      OUTPUT_LOAD='(1.0,-1.0)';
    'DQU1':
      PIN_NUMBER='(C3)';
      BIDIRECTIONAL='TRUE';
      INPUT_LOAD='(-0.01,0.01)';
      OUTPUT_LOAD='(1.0,-1.0)';
    'DQU2':
      PIN_NUMBER='(C8)';
      BIDIRECTIONAL='TRUE';
      INPUT_LOAD='(-0.01,0.01)';
      OUTPUT_LOAD='(1.0,-1.0)';
    'DQU3':
      PIN_NUMBER='(C2)';
      BIDIRECTIONAL='TRUE';
      INPUT_LOAD='(-0.01,0.01)';
      OUTPUT_LOAD='(1.0,-1.0)';
    'DQU4':
      PIN_NUMBER='(A7)';
      BIDIRECTIONAL='TRUE';
      INPUT_LOAD='(-0.01,0.01)';
      OUTPUT_LOAD='(1.0,-1.0)';
    'DQU5':
      PIN_NUMBER='(A2)';
      BIDIRECTIONAL='TRUE';
      INPUT_LOAD='(-0.01,0.01)';
      OUTPUT_LOAD='(1.0,-1.0)';
    'DQU6':
      PIN_NUMBER='(B8)';
      BIDIRECTIONAL='TRUE';
      INPUT_LOAD='(-0.01,0.01)';
      OUTPUT_LOAD='(1.0,-1.0)';
    'DQU7':
      PIN_NUMBER='(A3)';
      BIDIRECTIONAL='TRUE';
      INPUT_LOAD='(-0.01,0.01)';
      OUTPUT_LOAD='(1.0,-1.0)';
    'NC'<6>:
      PIN_NUMBER='(T7)';
      PINUSE='NC';
      NO_LOAD_CHECK='Both';
      NO_IO_CHECK='Both';
      NO_ASSERT_CHECK='TRUE';
      NO_DIR_CHECK='TRUE';
      ALLOW_CONNECT='TRUE';
    'NC'<5>:
      PIN_NUMBER='(T3)';
      PINUSE='NC';
      NO_LOAD_CHECK='Both';
      NO_IO_CHECK='Both';
      NO_ASSERT_CHECK='TRUE';
      NO_DIR_CHECK='TRUE';
      ALLOW_CONNECT='TRUE';
    'NC'<4>:
      PIN_NUMBER='(M7)';
      PINUSE='NC';
      NO_LOAD_CHECK='Both';
      NO_IO_CHECK='Both';
      NO_ASSERT_CHECK='TRUE';
      NO_DIR_CHECK='TRUE';
      ALLOW_CONNECT='TRUE';
    'NC'<3>:
      PIN_NUMBER='(L9)';
      PINUSE='NC';
      NO_LOAD_CHECK='Both';
      NO_IO_CHECK='Both';
      NO_ASSERT_CHECK='TRUE';
      NO_DIR_CHECK='TRUE';
      ALLOW_CONNECT='TRUE';
    'NC'<2>:
      PIN_NUMBER='(L1)';
      PINUSE='NC';
      NO_LOAD_CHECK='Both';
      NO_IO_CHECK='Both';
      NO_ASSERT_CHECK='TRUE';
      NO_DIR_CHECK='TRUE';
      ALLOW_CONNECT='TRUE';
    'NC'<1>:
      PIN_NUMBER='(J9)';
      PINUSE='NC';
      NO_LOAD_CHECK='Both';
      NO_IO_CHECK='Both';
      NO_ASSERT_CHECK='TRUE';
      NO_DIR_CHECK='TRUE';
      ALLOW_CONNECT='TRUE';
    'NC'<0>:
      PIN_NUMBER='(J1)';
      PINUSE='NC';
      NO_LOAD_CHECK='Both';
      NO_IO_CHECK='Both';
      NO_ASSERT_CHECK='TRUE';
      NO_DIR_CHECK='TRUE';
      ALLOW_CONNECT='TRUE';
    'ODT':
      PIN_NUMBER='(K1)';
      INPUT_LOAD='(-0.01,0.01)';
    'RAS_N':
      PIN_NUMBER='(J3)';
      INPUT_LOAD='(-0.01,0.01)';
    'RESET_N':
      PIN_NUMBER='(T2)';
      INPUT_LOAD='(-0.01,0.01)';
    'VDD'<8>:
      PIN_NUMBER='(R9)';
      PINUSE='POWER';
      NO_LOAD_CHECK='Both';
      NO_IO_CHECK='Both';
      NO_ASSERT_CHECK='TRUE';
      NO_DIR_CHECK='TRUE';
      ALLOW_CONNECT='TRUE';
    'VDD'<7>:
      PIN_NUMBER='(R1)';
      PINUSE='POWER';
      NO_LOAD_CHECK='Both';
      NO_IO_CHECK='Both';
      NO_ASSERT_CHECK='TRUE';
      NO_DIR_CHECK='TRUE';
      ALLOW_CONNECT='TRUE';
    'VDD'<6>:
      PIN_NUMBER='(N9)';
      PINUSE='POWER';
      NO_LOAD_CHECK='Both';
      NO_IO_CHECK='Both';
      NO_ASSERT_CHECK='TRUE';
      NO_DIR_CHECK='TRUE';
      ALLOW_CONNECT='TRUE';
    'VDD'<5>:
      PIN_NUMBER='(N1)';
      PINUSE='POWER';
      NO_LOAD_CHECK='Both';
      NO_IO_CHECK='Both';
      NO_ASSERT_CHECK='TRUE';
      NO_DIR_CHECK='TRUE';
      ALLOW_CONNECT='TRUE';
    'VDD'<4>:
      PIN_NUMBER='(K8)';
      PINUSE='POWER';
      NO_LOAD_CHECK='Both';
      NO_IO_CHECK='Both';
      NO_ASSERT_CHECK='TRUE';
      NO_DIR_CHECK='TRUE';
      ALLOW_CONNECT='TRUE';
    'VDD'<3>:
      PIN_NUMBER='(K2)';
      PINUSE='POWER';
      NO_LOAD_CHECK='Both';
      NO_IO_CHECK='Both';
      NO_ASSERT_CHECK='TRUE';
      NO_DIR_CHECK='TRUE';
      ALLOW_CONNECT='TRUE';
    'VDD'<2>:
      PIN_NUMBER='(G7)';
      PINUSE='POWER';
      NO_LOAD_CHECK='Both';
      NO_IO_CHECK='Both';
      NO_ASSERT_CHECK='TRUE';
      NO_DIR_CHECK='TRUE';
      ALLOW_CONNECT='TRUE';
    'VDD'<1>:
      PIN_NUMBER='(D9)';
      PINUSE='POWER';
      NO_LOAD_CHECK='Both';
      NO_IO_CHECK='Both';
      NO_ASSERT_CHECK='TRUE';
      NO_DIR_CHECK='TRUE';
      ALLOW_CONNECT='TRUE';
    'VDD'<0>:
      PIN_NUMBER='(B2)';
      PINUSE='POWER';
      NO_LOAD_CHECK='Both';
      NO_IO_CHECK='Both';
      NO_ASSERT_CHECK='TRUE';
      NO_DIR_CHECK='TRUE';
      ALLOW_CONNECT='TRUE';
    'VDDQ'<8>:
      PIN_NUMBER='(H9)';
      PINUSE='POWER';
      NO_LOAD_CHECK='Both';
      NO_IO_CHECK='Both';
      NO_ASSERT_CHECK='TRUE';
      NO_DIR_CHECK='TRUE';
      ALLOW_CONNECT='TRUE';
    'VDDQ'<7>:
      PIN_NUMBER='(H2)';
      PINUSE='POWER';
      NO_LOAD_CHECK='Both';
      NO_IO_CHECK='Both';
      NO_ASSERT_CHECK='TRUE';
      NO_DIR_CHECK='TRUE';
      ALLOW_CONNECT='TRUE';
    'VDDQ'<6>:
      PIN_NUMBER='(F1)';
      PINUSE='POWER';
      NO_LOAD_CHECK='Both';
      NO_IO_CHECK='Both';
      NO_ASSERT_CHECK='TRUE';
      NO_DIR_CHECK='TRUE';
      ALLOW_CONNECT='TRUE';
    'VDDQ'<5>:
      PIN_NUMBER='(E9)';
      PINUSE='POWER';
      NO_LOAD_CHECK='Both';
      NO_IO_CHECK='Both';
      NO_ASSERT_CHECK='TRUE';
      NO_DIR_CHECK='TRUE';
      ALLOW_CONNECT='TRUE';
    'VDDQ'<4>:
      PIN_NUMBER='(D2)';
      PINUSE='POWER';
      NO_LOAD_CHECK='Both';
      NO_IO_CHECK='Both';
      NO_ASSERT_CHECK='TRUE';
      NO_DIR_CHECK='TRUE';
      ALLOW_CONNECT='TRUE';
    'VDDQ'<3>:
      PIN_NUMBER='(C9)';
      PINUSE='POWER';
      NO_LOAD_CHECK='Both';
      NO_IO_CHECK='Both';
      NO_ASSERT_CHECK='TRUE';
      NO_DIR_CHECK='TRUE';
      ALLOW_CONNECT='TRUE';
    'VDDQ'<2>:
      PIN_NUMBER='(C1)';
      PINUSE='POWER';
      NO_LOAD_CHECK='Both';
      NO_IO_CHECK='Both';
      NO_ASSERT_CHECK='TRUE';
      NO_DIR_CHECK='TRUE';
      ALLOW_CONNECT='TRUE';
    'VDDQ'<1>:
      PIN_NUMBER='(A8)';
      PINUSE='POWER';
      NO_LOAD_CHECK='Both';
      NO_IO_CHECK='Both';
      NO_ASSERT_CHECK='TRUE';
      NO_DIR_CHECK='TRUE';
      ALLOW_CONNECT='TRUE';
    'VDDQ'<0>:
      PIN_NUMBER='(A1)';
      PINUSE='POWER';
      NO_LOAD_CHECK='Both';
      NO_IO_CHECK='Both';
      NO_ASSERT_CHECK='TRUE';
      NO_DIR_CHECK='TRUE';
      ALLOW_CONNECT='TRUE';
    'VREFCA':
      PIN_NUMBER='(M8)';
      BIDIRECTIONAL='TRUE';
      INPUT_LOAD='(-0.01,0.01)';
      OUTPUT_LOAD='(1.0,-1.0)';
    'VREFDQ':
      PIN_NUMBER='(H1)';
      BIDIRECTIONAL='TRUE';
      INPUT_LOAD='(-0.01,0.01)';
      OUTPUT_LOAD='(1.0,-1.0)';
    'VSS'<11>:
      PIN_NUMBER='(T9)';
      PINUSE='GROUND';
      NO_LOAD_CHECK='Both';
      NO_IO_CHECK='Both';
      NO_ASSERT_CHECK='TRUE';
      NO_DIR_CHECK='TRUE';
      ALLOW_CONNECT='TRUE';
    'VSS'<10>:
      PIN_NUMBER='(T1)';
      PINUSE='GROUND';
      NO_LOAD_CHECK='Both';
      NO_IO_CHECK='Both';
      NO_ASSERT_CHECK='TRUE';
      NO_DIR_CHECK='TRUE';
      ALLOW_CONNECT='TRUE';
    'VSS'<9>:
      PIN_NUMBER='(P9)';
      PINUSE='GROUND';
      NO_LOAD_CHECK='Both';
      NO_IO_CHECK='Both';
      NO_ASSERT_CHECK='TRUE';
      NO_DIR_CHECK='TRUE';
      ALLOW_CONNECT='TRUE';
    'VSS'<8>:
      PIN_NUMBER='(P1)';
      PINUSE='GROUND';
      NO_LOAD_CHECK='Both';
      NO_IO_CHECK='Both';
      NO_ASSERT_CHECK='TRUE';
      NO_DIR_CHECK='TRUE';
      ALLOW_CONNECT='TRUE';
    'VSS'<7>:
      PIN_NUMBER='(M9)';
      PINUSE='GROUND';
      NO_LOAD_CHECK='Both';
      NO_IO_CHECK='Both';
      NO_ASSERT_CHECK='TRUE';
      NO_DIR_CHECK='TRUE';
      ALLOW_CONNECT='TRUE';
    'VSS'<6>:
      PIN_NUMBER='(M1)';
      PINUSE='GROUND';
      NO_LOAD_CHECK='Both';
      NO_IO_CHECK='Both';
      NO_ASSERT_CHECK='TRUE';
      NO_DIR_CHECK='TRUE';
      ALLOW_CONNECT='TRUE';
    'VSS'<5>:
      PIN_NUMBER='(J8)';
      PINUSE='GROUND';
      NO_LOAD_CHECK='Both';
      NO_IO_CHECK='Both';
      NO_ASSERT_CHECK='TRUE';
      NO_DIR_CHECK='TRUE';
      ALLOW_CONNECT='TRUE';
    'VSS'<4>:
      PIN_NUMBER='(J2)';
      PINUSE='GROUND';
      NO_LOAD_CHECK='Both';
      NO_IO_CHECK='Both';
      NO_ASSERT_CHECK='TRUE';
      NO_DIR_CHECK='TRUE';
      ALLOW_CONNECT='TRUE';
    'VSS'<3>:
      PIN_NUMBER='(G8)';
      PINUSE='GROUND';
      NO_LOAD_CHECK='Both';
      NO_IO_CHECK='Both';
      NO_ASSERT_CHECK='TRUE';
      NO_DIR_CHECK='TRUE';
      ALLOW_CONNECT='TRUE';
    'VSS'<2>:
      PIN_NUMBER='(E1)';
      PINUSE='GROUND';
      NO_LOAD_CHECK='Both';
      NO_IO_CHECK='Both';
      NO_ASSERT_CHECK='TRUE';
      NO_DIR_CHECK='TRUE';
      ALLOW_CONNECT='TRUE';
    'VSS'<1>:
      PIN_NUMBER='(B3)';
      PINUSE='GROUND';
      NO_LOAD_CHECK='Both';
      NO_IO_CHECK='Both';
      NO_ASSERT_CHECK='TRUE';
      NO_DIR_CHECK='TRUE';
      ALLOW_CONNECT='TRUE';
    'VSS'<0>:
      PIN_NUMBER='(A9)';
      PINUSE='GROUND';
      NO_LOAD_CHECK='Both';
      NO_IO_CHECK='Both';
      NO_ASSERT_CHECK='TRUE';
      NO_DIR_CHECK='TRUE';
      ALLOW_CONNECT='TRUE';
    'VSSQ'<8>:
      PIN_NUMBER='(G9)';
      PINUSE='GROUND';
      NO_LOAD_CHECK='Both';
      NO_IO_CHECK='Both';
      NO_ASSERT_CHECK='TRUE';
      NO_DIR_CHECK='TRUE';
      ALLOW_CONNECT='TRUE';
    'VSSQ'<7>:
      PIN_NUMBER='(G1)';
      PINUSE='GROUND';
      NO_LOAD_CHECK='Both';
      NO_IO_CHECK='Both';
      NO_ASSERT_CHECK='TRUE';
      NO_DIR_CHECK='TRUE';
      ALLOW_CONNECT='TRUE';
    'VSSQ'<6>:
      PIN_NUMBER='(F9)';
      PINUSE='GROUND';
      NO_LOAD_CHECK='Both';
      NO_IO_CHECK='Both';
      NO_ASSERT_CHECK='TRUE';
      NO_DIR_CHECK='TRUE';
      ALLOW_CONNECT='TRUE';
    'VSSQ'<5>:
      PIN_NUMBER='(E8)';
      PINUSE='GROUND';
      NO_LOAD_CHECK='Both';
      NO_IO_CHECK='Both';
      NO_ASSERT_CHECK='TRUE';
      NO_DIR_CHECK='TRUE';
      ALLOW_CONNECT='TRUE';
    'VSSQ'<4>:
      PIN_NUMBER='(E2)';
      PINUSE='GROUND';
      NO_LOAD_CHECK='Both';
      NO_IO_CHECK='Both';
      NO_ASSERT_CHECK='TRUE';
      NO_DIR_CHECK='TRUE';
      ALLOW_CONNECT='TRUE';
    'VSSQ'<3>:
      PIN_NUMBER='(D8)';
      PINUSE='GROUND';
      NO_LOAD_CHECK='Both';
      NO_IO_CHECK='Both';
      NO_ASSERT_CHECK='TRUE';
      NO_DIR_CHECK='TRUE';
      ALLOW_CONNECT='TRUE';
    'VSSQ'<2>:
      PIN_NUMBER='(D1)';
      PINUSE='GROUND';
      NO_LOAD_CHECK='Both';
      NO_IO_CHECK='Both';
      NO_ASSERT_CHECK='TRUE';
      NO_DIR_CHECK='TRUE';
      ALLOW_CONNECT='TRUE';
    'VSSQ'<1>:
      PIN_NUMBER='(B9)';
      PINUSE='GROUND';
      NO_LOAD_CHECK='Both';
      NO_IO_CHECK='Both';
      NO_ASSERT_CHECK='TRUE';
      NO_DIR_CHECK='TRUE';
      ALLOW_CONNECT='TRUE';
    'VSSQ'<0>:
      PIN_NUMBER='(B1)';
      PINUSE='GROUND';
      NO_LOAD_CHECK='Both';
      NO_IO_CHECK='Both';
      NO_ASSERT_CHECK='TRUE';
      NO_DIR_CHECK='TRUE';
      ALLOW_CONNECT='TRUE';
    'WE_N':
      PIN_NUMBER='(L3)';
      INPUT_LOAD='(-0.01,0.01)';
    'ZQ':
      PIN_NUMBER='(L8)';
      BIDIRECTIONAL='TRUE';
      INPUT_LOAD='(-0.01,0.01)';
      OUTPUT_LOAD='(1.0,-1.0)';
  end_pin;
  body
    PART_NAME='K4B1G16';
    PHYS_DES_PREFIX='U';
  end_body;
end_primitive;

END.
